# BASEBOARD_FAB2 (Tioga Pass) — schematic netlist excerpt (pin names and nets, part order shuffled) for the footprints in the layout excerpt that follows; sources: Cadence DE-HDL packaged netlist, KiCad conversion of Wiwynn_Tioga_Pass_MB.brd

R25W32  120R2F-GP  1%  pkg RCL_GP  page 151 : \1\ = BMC_M_RAS_N ; \2\ = P1V2_AUX_BMC
R9M16  RES  2.0K 1% CHIP  pkg 0402  page 163 : A = P3V3_STBY ; B = SMB_PEHPCPU1_STBY_LVC3_R_SDA
R1R1  RES  0.0 5% CHIP  pkg 0402  page 139 : A = RST_PLTRST_N ; B = RST_PLTRST_SPRV_R_N

(kicad_pcb
	(version 20260206)
	(generator "pcbnew")
	(generator_version "10.0")
	(general
		(thickness 1.6)
		(legacy_teardrops no)
	)
	(paper "A4")
	(title_block
		(title "Wiwynn_Tioga_Pass_MB.brd")
		(comment 1 "Tioga Pass / footprints 4414-4416 of 4770")
	)
	(layers
		(0 "F.Cu" signal "TOP")
		(4 "In1.Cu" signal "L2GND")
		(6 "In2.Cu" signal "L3")
		(8 "In3.Cu" signal "L4GND")
		(10 "In4.Cu" signal "L5")
		(12 "In5.Cu" signal "L6GND")
		(14 "In6.Cu" signal "L7VCC")
		(16 "In7.Cu" signal "L8VCC")
		(18 "In8.Cu" signal "L9GND")
		(20 "In9.Cu" signal "L10")
		(22 "In10.Cu" signal "L11GND")
		(24 "In11.Cu" signal "L12")
		(26 "In12.Cu" signal "L13GND")
		(2 "B.Cu" signal "BOTTOM")
		(9 "F.Adhes" user "F.Adhesive")
		(11 "B.Adhes" user "B.Adhesive")
		(13 "F.Paste" user "Package Geometry/Pastemask Top")
		(15 "B.Paste" user "Package Geometry/Pastemask Bottom")
		(5 "F.SilkS" user "Ref Des/Silkscreen Top")
		(7 "B.SilkS" user "Ref Des/Silkscreen Bottom")
		(1 "F.Mask" user "Board Geometry/Soldermask Top")
		(3 "B.Mask" user "Board Geometry/Soldermask Bottom")
		(17 "Dwgs.User" user "User.Drawings")
		(19 "Cmts.User" user "User.Comments")
		(21 "Eco1.User" user "User.Eco1")
		(23 "Eco2.User" user "User.Eco2")
		(25 "Edge.Cuts" user "Board Geometry/Outline")
		(27 "Margin" user)
		(31 "F.CrtYd" user "Package Geometry/Place Bound Top")
		(29 "B.CrtYd" user "Package Geometry/Place Bound Bottom")
		(35 "F.Fab" user "Ref Des/Assembly Top")
		(33 "B.Fab" user "Ref Des/Assembly Bottom")
	)
	(footprint ""
		(layer "B.Cu")
		(at -1.44526 -119.46636 180)
		(property "Reference" "R9M16"
			(at 0 0 0)
			(layer "B.SilkS")
			(hide yes)
			(effects
				(font
					(size 1.27 1.27)
				)
				(justify mirror)
			)
		)
		(property "Value" ""
			(at 0 0 0)
			(layer "B.Fab")
			(effects
				(font
					(size 1.27 1.27)
				)
				(justify mirror)
			)
		)
		(duplicate_pad_numbers_are_jumpers no)
		(fp_rect
			(start 0.2794 -0.1016)
			(end -0.2794 0.9906)
			(stroke
				(width 0)
				(type default)
			)
			(fill no)
			(layer "B.CrtYd")
		)
		(fp_line
			(start 0.2794 0.9906)
			(end -0.2794 0.9906)
			(stroke
				(width 0.1)
				(type default)
			)
			(layer "B.Fab")
		)
		(fp_line
			(start 0.2794 -0.1016)
			(end 0.2794 0.9906)
			(stroke
				(width 0.1)
				(type default)
			)
			(layer "B.Fab")
		)
		(fp_line
			(start -0.2794 0.9906)
			(end -0.2794 -0.1016)
			(stroke
				(width 0.1)
				(type default)
			)
			(layer "B.Fab")
		)
		(fp_line
			(start -0.2794 -0.1016)
			(end 0.2794 -0.1016)
			(stroke
				(width 0.1)
				(type default)
			)
			(layer "B.Fab")
		)
		(pad "1" smd rect
			(at 0 0)
			(size 0.508 0.508)
			(layers "B.Cu" "B.Mask" "B.Paste")
			(net "P3V3_STBY")
		)
		(pad "2" smd rect
			(at 0 0.889)
			(size 0.508 0.508)
			(layers "B.Cu" "B.Mask" "B.Paste")
			(net "SMB_PEHPCPU1_STBY_LVC3_R_SDA")
		)
		(zone
			(layer "B.Cu")
			(hatch none 0.5)
			(connect_pads
				(clearance 0)
			)
			(min_thickness 0.25)
			(keepout
				(tracks allowed)
				(vias not_allowed)
				(pads allowed)
				(copperpour not_allowed)
				(footprints allowed)
			)
			(placement
				(enabled no)
				(sheetname "")
			)
			(fill
				(thermal_gap 0.5)
				(thermal_bridge_width 0.5)
				(island_removal_mode 0)
			)
			(polygon
				(pts
					(xy -1.69926 -119.72036) (xy -1.19126 -119.72036) (xy -1.19126 -120.10136) (xy -1.69926 -120.10136)
				)
			)
		)
		(zone
			(layer "B.Cu")
			(hatch none 0.5)
			(connect_pads
				(clearance 0)
			)
			(min_thickness 0.25)
			(keepout
				(tracks not_allowed)
				(vias allowed)
				(pads allowed)
				(copperpour not_allowed)
				(footprints allowed)
			)
			(placement
				(enabled no)
				(sheetname "")
			)
			(fill
				(thermal_gap 0.5)
				(thermal_bridge_width 0.5)
				(island_removal_mode 0)
			)
			(polygon
				(pts
					(xy -1.69926 -119.72036) (xy -1.19126 -119.72036) (xy -1.19126 -120.10136) (xy -1.69926 -120.10136)
				)
			)
		)
	)
	(footprint ""
		(layer "B.Cu")
		(at 484.9749 -49.8602 90)
		(property "Reference" "R1R1"
			(at 0 0 90)
			(layer "B.SilkS")
			(hide yes)
			(effects
				(font
					(size 1.27 1.27)
				)
				(justify mirror)
			)
		)
		(property "Value" ""
			(at 0 0 90)
			(layer "B.Fab")
			(effects
				(font
					(size 1.27 1.27)
				)
				(justify mirror)
			)
		)
		(duplicate_pad_numbers_are_jumpers no)
		(fp_poly
			(pts
				(xy 0.2794 -0.1016) (xy -0.2794 -0.1016) (xy -0.2794 0.9906) (xy 0.2794 0.9906)
			)
			(stroke
				(width 0)
				(type default)
			)
			(fill no)
			(layer "B.CrtYd")
		)
		(fp_line
			(start 0.2794 -0.1016)
			(end 0.2794 0.9906)
			(stroke
				(width 0.1)
				(type default)
			)
			(layer "B.Fab")
		)
		(fp_line
			(start -0.2794 -0.1016)
			(end 0.2794 -0.1016)
			(stroke
				(width 0.1)
				(type default)
			)
			(layer "B.Fab")
		)
		(fp_line
			(start 0.2794 0.9906)
			(end -0.2794 0.9906)
			(stroke
				(width 0.1)
				(type default)
			)
			(layer "B.Fab")
		)
		(fp_line
			(start -0.2794 0.9906)
			(end -0.2794 -0.1016)
			(stroke
				(width 0.1)
				(type default)
			)
			(layer "B.Fab")
		)
		(pad "1" smd rect
			(at 0 0 270)
			(size 0.508 0.508)
			(layers "B.Cu" "B.Mask" "B.Paste")
			(net "RST_PLTRST_N")
		)
		(pad "2" smd rect
			(at 0 0.889 270)
			(size 0.508 0.508)
			(layers "B.Cu" "B.Mask" "B.Paste")
			(net "RST_PLTRST_SPRV_R_N")
		)
		(zone
			(layer "B.Cu")
			(hatch none 0.5)
			(connect_pads
				(clearance 0)
			)
			(min_thickness 0.25)
			(keepout
				(tracks allowed)
				(vias not_allowed)
				(pads allowed)
				(copperpour not_allowed)
				(footprints allowed)
			)
			(placement
				(enabled no)
				(sheetname "")
			)
			(fill
				(thermal_gap 0.5)
				(thermal_bridge_width 0.5)
				(island_removal_mode 0)
			)
			(polygon
				(pts
					(xy 485.2289 -50.1142) (xy 485.2289 -49.6062) (xy 485.6099 -49.6062) (xy 485.6099 -50.1142)
				)
			)
		)
		(zone
			(layer "B.Cu")
			(hatch none 0.5)
			(connect_pads
				(clearance 0)
			)
			(min_thickness 0.25)
			(keepout
				(tracks not_allowed)
				(vias allowed)
				(pads allowed)
				(copperpour not_allowed)
				(footprints allowed)
			)
			(placement
				(enabled no)
				(sheetname "")
			)
			(fill
				(thermal_gap 0.5)
				(thermal_bridge_width 0.5)
				(island_removal_mode 0)
			)
			(polygon
				(pts
					(xy 485.6099 -50.1142) (xy 485.6099 -49.6062) (xy 485.2289 -49.6062) (xy 485.2289 -50.1142)
				)
			)
		)
	)
	(footprint ""
		(layer "B.Cu")
		(at 448.55638 -35.8775 90)
		(property "Reference" "R25W32"
			(at 0 0 90)
			(layer "B.SilkS")
			(hide yes)
			(effects
				(font
					(size 1.27 1.27)
				)
				(justify mirror)
			)
		)
		(property "Value" "*"
			(at -0.064008 -4.108196 90)
			(unlocked yes)
			(layer "B.Fab")
			(hide yes)
			(effects
				(font
					(size 1.27 1.016)
					(thickness 0.1524)
				)
				(justify mirror)
			)
		)
		(property "Device Type" "120R2F-GP_RCL_GP-120R2F-GP,64.A"
			(at -0.064008 -5.632196 90)
			(unlocked yes)
			(layer "B.Fab")
			(hide yes)
			(effects
				(font
					(size 1.27 1.016)
					(thickness 0.1524)
				)
				(justify mirror)
			)
		)
		(duplicate_pad_numbers_are_jumpers no)
		(fp_line
			(start 0.508 -0.9398)
			(end 0.508 0.9398)
			(stroke
				(width 0.1524)
				(type default)
			)
			(layer "B.SilkS")
		)
		(fp_line
			(start -0.508 -0.9398)
			(end 0.508 -0.9398)
			(stroke
				(width 0.1524)
				(type default)
			)
			(layer "B.SilkS")
		)
		(fp_rect
			(start 0.508 0.9398)
			(end -0.508 -0.9398)
			(stroke
				(width 0)
				(type default)
			)
			(fill no)
			(layer "B.CrtYd")
		)
		(fp_rect
			(start 0.508 0.9398)
			(end -0.508 -0.9398)
			(stroke
				(width 0)
				(type default)
			)
			(fill no)
			(layer "B.Fab")
		)
		(pad "1" smd custom
			(at 0 -0.4445 270)
			(size 0.1397 0.1397)
			(layers "B.Cu" "B.Mask" "B.Paste")
			(net "BMC_M_RAS_N")
			(options
				(clearance outline)
				(anchor circle)
			)
			(primitives
				(gr_poly
					(pts
						(arc
							(start -0.1778 0.2794)
							(mid -0.249642 0.249642)
							(end -0.2794 0.1778)
						)
						(arc
							(start -0.2794 -0.1778)
							(mid -0.249642 -0.249642)
							(end -0.1778 -0.2794)
						)
						(arc
							(start 0.1778 -0.2794)
							(mid 0.249642 -0.249642)
							(end 0.2794 -0.1778)
						)
						(arc
							(start 0.2794 0.1778)
							(mid 0.249642 0.249642)
							(end 0.1778 0.2794)
						)
					)
					(width 0)
					(fill yes)
				)
			)
		)
		(pad "2" smd custom
			(at 0 0.4445 270)
			(size 0.1397 0.1397)
			(layers "B.Cu" "B.Mask" "B.Paste")
			(net "P1V2_AUX_BMC")
			(options
				(clearance outline)
				(anchor circle)
			)
			(primitives
				(gr_poly
					(pts
						(arc
							(start -0.1778 0.2794)
							(mid -0.249642 0.249642)
							(end -0.2794 0.1778)
						)
						(arc
							(start -0.2794 -0.1778)
							(mid -0.249642 -0.249642)
							(end -0.1778 -0.2794)
						)
						(arc
							(start 0.1778 -0.2794)
							(mid 0.249642 -0.249642)
							(end 0.2794 -0.1778)
						)
						(arc
							(start 0.2794 0.1778)
							(mid 0.249642 0.249642)
							(end 0.1778 0.2794)
						)
					)
					(width 0)
					(fill yes)
				)
			)
		)
	)
)
